# T6G (Grand Teton) — schematic netlist excerpt (pin names and nets, part order shuffled) for the footprints in the layout excerpt that follows; sources: Cadence DE-HDL packaged netlist, KiCad conversion of 04192023_DAF0TMB3IC0_F0TG_MB_C_brd_V02_OCP.brd

U219  74LVC1G07GV  IC  pkg SC-74A_2-9X1-5  page 139
  NC1  = NC_U219_NC1
  A  = OCP_V3_2_WAKE_BUFF_R_N
  GND  = GND
  Y  = IRQ_LVC3_V3_2_WAKE_BUF_N
  VCC  = P3V3_AUX

R2696  Q_RES  1K 1% CHIP  pkg 0402LF  page 245 : A = TCA9539_0_ADD0 ; B = GND

(kicad_pcb
	(version 20260206)
	(generator "pcbnew")
	(generator_version "10.0")
	(general
		(thickness 1.6)
		(legacy_teardrops no)
	)
	(paper "A4")
	(title_block
		(title "04192023_DAF0TMB3IC0_F0TG_MB_C_brd_V02_OCP.brd")
		(comment 1 "Grand Teton / footprints 1140-1141 of 8354")
	)
	(layers
		(0 "F.Cu" signal "TOP")
		(4 "In1.Cu" signal "GND")
		(6 "In2.Cu" signal "IN1")
		(8 "In3.Cu" signal "GND1")
		(10 "In4.Cu" signal "IN2")
		(12 "In5.Cu" signal "GND2")
		(14 "In6.Cu" signal "IN3")
		(16 "In7.Cu" signal "GND3")
		(18 "In8.Cu" signal "VCC")
		(20 "In9.Cu" signal "VCC1")
		(22 "In10.Cu" signal "GND4")
		(24 "In11.Cu" signal "IN4")
		(26 "In12.Cu" signal "GND5")
		(28 "In13.Cu" signal "IN5")
		(30 "In14.Cu" signal "GND6")
		(32 "In15.Cu" signal "IN6")
		(34 "In16.Cu" signal "GND7")
		(2 "B.Cu" signal "BOTTOM")
		(9 "F.Adhes" user "F.Adhesive")
		(11 "B.Adhes" user "B.Adhesive")
		(13 "F.Paste" user "Package Geometry/Pastemask Top")
		(15 "B.Paste" user "Package Geometry/Pastemask Bottom")
		(5 "F.SilkS" user "Ref Des/Silkscreen Top")
		(7 "B.SilkS" user "Ref Des/Silkscreen Bottom")
		(1 "F.Mask" user "Board Geometry/Soldermask Top")
		(3 "B.Mask" user "Board Geometry/Soldermask Bottom")
		(17 "Dwgs.User" user "User.Drawings")
		(19 "Cmts.User" user "User.Comments")
		(21 "Eco1.User" user "User.Eco1")
		(23 "Eco2.User" user "User.Eco2")
		(25 "Edge.Cuts" user "Board Geometry/Outline")
		(27 "Margin" user)
		(31 "F.CrtYd" user "Package Geometry/Place Bound Top")
		(29 "B.CrtYd" user "Package Geometry/Place Bound Bottom")
		(35 "F.Fab" user "Ref Des/Assembly Top")
		(33 "B.Fab" user "Ref Des/Assembly Bottom")
	)
	(footprint ""
		(layer "F.Cu")
		(at 177.378106 -427.226984 180)
		(property "Reference" "R2696"
			(at 0 0 180)
			(layer "F.SilkS")
			(hide yes)
			(effects
				(font
					(size 1.27 1.27)
				)
			)
		)
		(property "Value" ""
			(at 0 0 180)
			(layer "F.Fab")
			(effects
				(font
					(size 1.27 1.27)
				)
			)
		)
		(duplicate_pad_numbers_are_jumpers no)
		(fp_line
			(start 0.7874 0.4064)
			(end -0.7874 0.4064)
			(stroke
				(width 0.1524)
				(type default)
			)
			(layer "F.SilkS")
		)
		(fp_line
			(start 0.7874 -0.4064)
			(end 0.7874 0.4064)
			(stroke
				(width 0.1524)
				(type default)
			)
			(layer "F.SilkS")
		)
		(fp_line
			(start -0.7874 0.4064)
			(end -0.7874 -0.4064)
			(stroke
				(width 0.1524)
				(type default)
			)
			(layer "F.SilkS")
		)
		(fp_line
			(start -0.7874 -0.4064)
			(end 0.7874 -0.4064)
			(stroke
				(width 0.1524)
				(type default)
			)
			(layer "F.SilkS")
		)
		(fp_line
			(start 0.67945 0.3048)
			(end 0.120396 0.3048)
			(stroke
				(width 0.1)
				(type default)
			)
			(layer "F.Fab")
		)
		(fp_line
			(start 0.67945 -0.3048)
			(end 0.67945 0.3048)
			(stroke
				(width 0.1)
				(type default)
			)
			(layer "F.Fab")
		)
		(fp_line
			(start 0.12065 -0.2794)
			(end 0.12065 -0.3048)
			(stroke
				(width 0.1)
				(type default)
			)
			(layer "F.Fab")
		)
		(fp_line
			(start 0.12065 -0.3048)
			(end 0.67945 -0.3048)
			(stroke
				(width 0.1)
				(type default)
			)
			(layer "F.Fab")
		)
		(fp_line
			(start 0.120396 0.3048)
			(end 0.120396 0.2794)
			(stroke
				(width 0.1)
				(type default)
			)
			(layer "F.Fab")
		)
		(fp_line
			(start 0.120396 0.2794)
			(end -0.12065 0.2794)
			(stroke
				(width 0.1)
				(type default)
			)
			(layer "F.Fab")
		)
		(fp_line
			(start -0.12065 0.3048)
			(end -0.67945 0.3048)
			(stroke
				(width 0.1)
				(type default)
			)
			(layer "F.Fab")
		)
		(fp_line
			(start -0.12065 0.2794)
			(end -0.12065 0.3048)
			(stroke
				(width 0.1)
				(type default)
			)
			(layer "F.Fab")
		)
		(fp_line
			(start -0.12065 -0.2794)
			(end 0.12065 -0.2794)
			(stroke
				(width 0.1)
				(type default)
			)
			(layer "F.Fab")
		)
		(fp_line
			(start -0.12065 -0.305054)
			(end -0.12065 -0.2794)
			(stroke
				(width 0.1)
				(type default)
			)
			(layer "F.Fab")
		)
		(fp_line
			(start -0.67945 0.3048)
			(end -0.67945 -0.305054)
			(stroke
				(width 0.1)
				(type default)
			)
			(layer "F.Fab")
		)
		(fp_line
			(start -0.67945 -0.305054)
			(end -0.12065 -0.305054)
			(stroke
				(width 0.1)
				(type default)
			)
			(layer "F.Fab")
		)
		(pad "1" smd circle
			(at -0.40005 0 180)
			(size 0 0)
			(layers "F.Cu" "F.Mask" "F.Paste")
			(net "TCA9539_0_ADD0")
		)
		(pad "2" smd circle
			(at 0.40005 0 180)
			(size 0 0)
			(layers "F.Cu" "F.Mask" "F.Paste")
			(net "GND")
		)
	)
	(footprint ""
		(layer "F.Cu")
		(at 95.433642 -35.279838)
		(property "Reference" "U219"
			(at -1.20904 2.445512 0)
			(unlocked yes)
			(layer "F.SilkS")
			(effects
				(font
					(size 0.7874 0.5842)
					(thickness 0.1524)
				)
				(justify left)
			)
		)
		(property "Value" ""
			(at 0 0 0)
			(layer "F.Fab")
			(effects
				(font
					(size 1.27 1.27)
				)
			)
		)
		(duplicate_pad_numbers_are_jumpers no)
		(fp_line
			(start -1.733296 -1.549908)
			(end -1.733296 1.549908)
			(stroke
				(width 0.1524)
				(type default)
			)
			(layer "F.SilkS")
		)
		(fp_line
			(start -1.733296 1.549908)
			(end 1.733296 1.549908)
			(stroke
				(width 0.1524)
				(type default)
			)
			(layer "F.SilkS")
		)
		(fp_line
			(start -0.660908 -1.549908)
			(end -1.733296 -1.549908)
			(stroke
				(width 0.1524)
				(type default)
			)
			(layer "F.SilkS")
		)
		(fp_line
			(start 0 -0.889)
			(end -0.660908 -1.549908)
			(stroke
				(width 0.1524)
				(type default)
			)
			(layer "F.SilkS")
		)
		(fp_line
			(start 0.660908 -1.549908)
			(end 0 -0.889)
			(stroke
				(width 0.1524)
				(type default)
			)
			(layer "F.SilkS")
		)
		(fp_line
			(start 1.733296 -1.549908)
			(end 0.660908 -1.549908)
			(stroke
				(width 0.1524)
				(type default)
			)
			(layer "F.SilkS")
		)
		(fp_line
			(start 1.733296 1.549908)
			(end 1.733296 -1.549908)
			(stroke
				(width 0.1524)
				(type default)
			)
			(layer "F.SilkS")
		)
		(fp_poly
			(pts
				(xy -2.4384 -0.69596) (xy -2.4384 -1.20396) (xy -1.9304 -0.94996)
			)
			(stroke
				(width 0)
				(type default)
			)
			(fill yes)
			(layer "F.SilkS")
		)
		(fp_line
			(start -0.849884 -1.549908)
			(end -0.849884 1.549908)
			(stroke
				(width 0.1)
				(type default)
			)
			(layer "F.Fab")
		)
		(fp_line
			(start -0.849884 1.549908)
			(end 0.849884 1.549908)
			(stroke
				(width 0.1)
				(type default)
			)
			(layer "F.Fab")
		)
		(fp_line
			(start 0.849884 -1.549908)
			(end -0.849884 -1.549908)
			(stroke
				(width 0.1)
				(type default)
			)
			(layer "F.Fab")
		)
		(fp_line
			(start 0.849884 1.549908)
			(end 0.849884 -1.549908)
			(stroke
				(width 0.1)
				(type default)
			)
			(layer "F.Fab")
		)
		(fp_poly
			(pts
				(xy -2.4384 -1.20396) (xy -2.4384 -0.69596) (xy -1.9304 -0.94996)
			)
			(stroke
				(width 0)
				(type default)
			)
			(fill yes)
			(layer "F.Fab")
		)
		(pad "1" smd rect
			(at -1.199896 -0.94996 270)
			(size 0.5588 0.8128)
			(layers "F.Cu" "F.Mask" "F.Paste")
			(net "NC_U219_NC1")
		)
		(pad "2" smd rect
			(at -1.199896 0 270)
			(size 0.5588 0.8128)
			(layers "F.Cu" "F.Mask" "F.Paste")
			(net "OCP_V3_2_WAKE_BUFF_R_N")
		)
		(pad "3" smd rect
			(at -1.199896 0.94996 270)
			(size 0.5588 0.8128)
			(layers "F.Cu" "F.Mask" "F.Paste")
			(net "GND")
		)
		(pad "4" smd rect
			(at 1.199896 0.94996 270)
			(size 0.5588 0.8128)
			(layers "F.Cu" "F.Mask" "F.Paste")
			(net "IRQ_LVC3_V3_2_WAKE_BUF_N")
		)
		(pad "5" smd rect
			(at 1.199896 -0.94996 270)
			(size 0.5588 0.8128)
			(layers "F.Cu" "F.Mask" "F.Paste")
			(net "P3V3_AUX")
		)
	)
)
